(kicad_pcb
	(version 20260206)
	(generator "pcbnew")
	(generator_version "10.0")
	(general
		(thickness 1.6)
		(legacy_teardrops no)
	)
	(paper "A4")
	(title_block
		(title "01162023_DA0F0TEBIF0_F0T_Expander_BD_F_brd_V02_OCP.brd")
		(comment 1 "Grand Teton / footprints 9676-9684 of 9728")
	)
	(layers
		(0 "F.Cu" signal "TOP")
		(4 "In1.Cu" signal "GND")
		(6 "In2.Cu" signal "VCC")
		(8 "In3.Cu" signal "VCC1")
		(10 "In4.Cu" signal "GND1")
		(12 "In5.Cu" signal "IN1")
		(14 "In6.Cu" signal "GND2")
		(16 "In7.Cu" signal "IN2")
		(18 "In8.Cu" signal "GND3")
		(20 "In9.Cu" signal "IN3")
		(22 "In10.Cu" signal "GND4")
		(24 "In11.Cu" signal "IN4")
		(26 "In12.Cu" signal "GND5")
		(28 "In13.Cu" signal "IN5")
		(30 "In14.Cu" signal "GND6")
		(32 "In15.Cu" signal "IN6")
		(34 "In16.Cu" signal "GND7")
		(2 "B.Cu" signal "BOTTOM")
		(9 "F.Adhes" user "F.Adhesive")
		(11 "B.Adhes" user "B.Adhesive")
		(13 "F.Paste" user "Package Geometry/Pastemask Top")
		(15 "B.Paste" user "Package Geometry/Pastemask Bottom")
		(5 "F.SilkS" user "Ref Des/Silkscreen Top")
		(7 "B.SilkS" user "Ref Des/Silkscreen Bottom")
		(1 "F.Mask" user "Board Geometry/Soldermask Top")
		(3 "B.Mask" user "Board Geometry/Soldermask Bottom")
		(17 "Dwgs.User" user "User.Drawings")
		(19 "Cmts.User" user "User.Comments")
		(21 "Eco1.User" user "User.Eco1")
		(23 "Eco2.User" user "User.Eco2")
		(25 "Edge.Cuts" user "Board Geometry/Outline")
		(27 "Margin" user)
		(31 "F.CrtYd" user "Package Geometry/Place Bound Top")
		(29 "B.CrtYd" user "Package Geometry/Place Bound Bottom")
		(35 "F.Fab" user "Ref Des/Assembly Top")
		(33 "B.Fab" user "Ref Des/Assembly Bottom")
	)
	(footprint ""
		(layer "B.Cu")
		(at 172.983906 -308.724808 -90)
		(property "Reference" "R1323"
			(at 0 0 90)
			(layer "B.SilkS")
			(hide yes)
			(effects
				(font
					(size 1.27 1.27)
				)
				(justify mirror)
			)
		)
		(property "Value" ""
			(at 0 0 90)
			(layer "B.Fab")
			(effects
				(font
					(size 1.27 1.27)
				)
				(justify mirror)
			)
		)
		(duplicate_pad_numbers_are_jumpers no)
		(fp_line
			(start -0.7874 0.4064)
			(end 0.7874 0.4064)
			(stroke
				(width 0.1524)
				(type default)
			)
			(layer "B.SilkS")
		)
		(fp_line
			(start 0.7874 0.4064)
			(end 0.7874 -0.4064)
			(stroke
				(width 0.1524)
				(type default)
			)
			(layer "B.SilkS")
		)
		(fp_line
			(start -0.7874 -0.4064)
			(end -0.7874 0.4064)
			(stroke
				(width 0.1524)
				(type default)
			)
			(layer "B.SilkS")
		)
		(fp_line
			(start 0.7874 -0.4064)
			(end -0.7874 -0.4064)
			(stroke
				(width 0.1524)
				(type default)
			)
			(layer "B.SilkS")
		)
		(fp_line
			(start -0.67945 0.3048)
			(end -0.120396 0.3048)
			(stroke
				(width 0.1)
				(type default)
			)
			(layer "B.Fab")
		)
		(fp_line
			(start -0.120396 0.3048)
			(end -0.120396 0.2794)
			(stroke
				(width 0.1)
				(type default)
			)
			(layer "B.Fab")
		)
		(fp_line
			(start 0.12065 0.3048)
			(end 0.67945 0.3048)
			(stroke
				(width 0.1)
				(type default)
			)
			(layer "B.Fab")
		)
		(fp_line
			(start 0.67945 0.3048)
			(end 0.67945 -0.305054)
			(stroke
				(width 0.1)
				(type default)
			)
			(layer "B.Fab")
		)
		(fp_line
			(start -0.120396 0.2794)
			(end 0.12065 0.2794)
			(stroke
				(width 0.1)
				(type default)
			)
			(layer "B.Fab")
		)
		(fp_line
			(start 0.12065 0.2794)
			(end 0.12065 0.3048)
			(stroke
				(width 0.1)
				(type default)
			)
			(layer "B.Fab")
		)
		(fp_line
			(start -0.12065 -0.2794)
			(end -0.12065 -0.3048)
			(stroke
				(width 0.1)
				(type default)
			)
			(layer "B.Fab")
		)
		(fp_line
			(start 0.12065 -0.2794)
			(end -0.12065 -0.2794)
			(stroke
				(width 0.1)
				(type default)
			)
			(layer "B.Fab")
		)
		(fp_line
			(start -0.67945 -0.3048)
			(end -0.67945 0.3048)
			(stroke
				(width 0.1)
				(type default)
			)
			(layer "B.Fab")
		)
		(fp_line
			(start -0.12065 -0.3048)
			(end -0.67945 -0.3048)
			(stroke
				(width 0.1)
				(type default)
			)
			(layer "B.Fab")
		)
		(fp_line
			(start 0.12065 -0.305054)
			(end 0.12065 -0.2794)
			(stroke
				(width 0.1)
				(type default)
			)
			(layer "B.Fab")
		)
		(fp_line
			(start 0.67945 -0.305054)
			(end 0.12065 -0.305054)
			(stroke
				(width 0.1)
				(type default)
			)
			(layer "B.Fab")
		)
		(pad "1" smd circle
			(at 0.40005 0 90)
			(size 0 0)
			(layers "B.Cu" "B.Mask" "B.Paste")
			(net "TP_PEX1_TRST_L")
		)
		(pad "2" smd circle
			(at -0.40005 0 90)
			(size 0 0)
			(layers "B.Cu" "B.Mask" "B.Paste")
			(net "GND")
		)
	)
	(footprint ""
		(layer "B.Cu")
		(at 101.823266 -356.061772 -90)
		(property "Reference" "R6371"
			(at 0 0 90)
			(layer "B.SilkS")
			(hide yes)
			(effects
				(font
					(size 1.27 1.27)
				)
				(justify mirror)
			)
		)
		(property "Value" ""
			(at 0 0 90)
			(layer "B.Fab")
			(effects
				(font
					(size 1.27 1.27)
				)
				(justify mirror)
			)
		)
		(duplicate_pad_numbers_are_jumpers no)
		(fp_line
			(start -0.7874 0.4064)
			(end 0.7874 0.4064)
			(stroke
				(width 0.1524)
				(type default)
			)
			(layer "B.SilkS")
		)
		(fp_line
			(start 0.7874 0.4064)
			(end 0.7874 -0.4064)
			(stroke
				(width 0.1524)
				(type default)
			)
			(layer "B.SilkS")
		)
		(fp_line
			(start -0.7874 -0.4064)
			(end -0.7874 0.4064)
			(stroke
				(width 0.1524)
				(type default)
			)
			(layer "B.SilkS")
		)
		(fp_line
			(start 0.7874 -0.4064)
			(end -0.7874 -0.4064)
			(stroke
				(width 0.1524)
				(type default)
			)
			(layer "B.SilkS")
		)
		(fp_line
			(start -0.67945 0.3048)
			(end -0.120396 0.3048)
			(stroke
				(width 0.1)
				(type default)
			)
			(layer "B.Fab")
		)
		(fp_line
			(start -0.120396 0.3048)
			(end -0.120396 0.2794)
			(stroke
				(width 0.1)
				(type default)
			)
			(layer "B.Fab")
		)
		(fp_line
			(start 0.12065 0.3048)
			(end 0.67945 0.3048)
			(stroke
				(width 0.1)
				(type default)
			)
			(layer "B.Fab")
		)
		(fp_line
			(start 0.67945 0.3048)
			(end 0.67945 -0.305054)
			(stroke
				(width 0.1)
				(type default)
			)
			(layer "B.Fab")
		)
		(fp_line
			(start -0.120396 0.2794)
			(end 0.12065 0.2794)
			(stroke
				(width 0.1)
				(type default)
			)
			(layer "B.Fab")
		)
		(fp_line
			(start 0.12065 0.2794)
			(end 0.12065 0.3048)
			(stroke
				(width 0.1)
				(type default)
			)
			(layer "B.Fab")
		)
		(fp_line
			(start -0.12065 -0.2794)
			(end -0.12065 -0.3048)
			(stroke
				(width 0.1)
				(type default)
			)
			(layer "B.Fab")
		)
		(fp_line
			(start 0.12065 -0.2794)
			(end -0.12065 -0.2794)
			(stroke
				(width 0.1)
				(type default)
			)
			(layer "B.Fab")
		)
		(fp_line
			(start -0.67945 -0.3048)
			(end -0.67945 0.3048)
			(stroke
				(width 0.1)
				(type default)
			)
			(layer "B.Fab")
		)
		(fp_line
			(start -0.12065 -0.3048)
			(end -0.67945 -0.3048)
			(stroke
				(width 0.1)
				(type default)
			)
			(layer "B.Fab")
		)
		(fp_line
			(start 0.12065 -0.305054)
			(end 0.12065 -0.2794)
			(stroke
				(width 0.1)
				(type default)
			)
			(layer "B.Fab")
		)
		(fp_line
			(start 0.67945 -0.305054)
			(end 0.12065 -0.305054)
			(stroke
				(width 0.1)
				(type default)
			)
			(layer "B.Fab")
		)
		(pad "1" smd circle
			(at 0.40005 0 90)
			(size 0 0)
			(layers "B.Cu" "B.Mask" "B.Paste")
			(net "PEX_S3_REF_CLK_BUFFER_EN_N")
		)
		(pad "2" smd circle
			(at -0.40005 0 90)
			(size 0 0)
			(layers "B.Cu" "B.Mask" "B.Paste")
			(net "GND")
		)
	)
	(footprint ""
		(layer "B.Cu")
		(at 109.543088 -351.796604)
		(property "Reference" "R6382"
			(at 0 0 0)
			(layer "B.SilkS")
			(hide yes)
			(effects
				(font
					(size 1.27 1.27)
				)
				(justify mirror)
			)
		)
		(property "Value" ""
			(at 0 0 0)
			(layer "B.Fab")
			(effects
				(font
					(size 1.27 1.27)
				)
				(justify mirror)
			)
		)
		(duplicate_pad_numbers_are_jumpers no)
		(fp_line
			(start -0.7874 -0.4064)
			(end -0.7874 0.4064)
			(stroke
				(width 0.1524)
				(type default)
			)
			(layer "B.SilkS")
		)
		(fp_line
			(start -0.7874 0.4064)
			(end 0.7874 0.4064)
			(stroke
				(width 0.1524)
				(type default)
			)
			(layer "B.SilkS")
		)
		(fp_line
			(start 0.7874 -0.4064)
			(end -0.7874 -0.4064)
			(stroke
				(width 0.1524)
				(type default)
			)
			(layer "B.SilkS")
		)
		(fp_line
			(start 0.7874 0.4064)
			(end 0.7874 -0.4064)
			(stroke
				(width 0.1524)
				(type default)
			)
			(layer "B.SilkS")
		)
		(fp_line
			(start -0.67945 -0.3048)
			(end -0.67945 0.3048)
			(stroke
				(width 0.1)
				(type default)
			)
			(layer "B.Fab")
		)
		(fp_line
			(start -0.67945 0.3048)
			(end -0.120396 0.3048)
			(stroke
				(width 0.1)
				(type default)
			)
			(layer "B.Fab")
		)
		(fp_line
			(start -0.12065 -0.3048)
			(end -0.67945 -0.3048)
			(stroke
				(width 0.1)
				(type default)
			)
			(layer "B.Fab")
		)
		(fp_line
			(start -0.12065 -0.2794)
			(end -0.12065 -0.3048)
			(stroke
				(width 0.1)
				(type default)
			)
			(layer "B.Fab")
		)
		(fp_line
			(start -0.120396 0.2794)
			(end 0.12065 0.2794)
			(stroke
				(width 0.1)
				(type default)
			)
			(layer "B.Fab")
		)
		(fp_line
			(start -0.120396 0.3048)
			(end -0.120396 0.2794)
			(stroke
				(width 0.1)
				(type default)
			)
			(layer "B.Fab")
		)
		(fp_line
			(start 0.12065 -0.305054)
			(end 0.12065 -0.2794)
			(stroke
				(width 0.1)
				(type default)
			)
			(layer "B.Fab")
		)
		(fp_line
			(start 0.12065 -0.2794)
			(end -0.12065 -0.2794)
			(stroke
				(width 0.1)
				(type default)
			)
			(layer "B.Fab")
		)
		(fp_line
			(start 0.12065 0.2794)
			(end 0.12065 0.3048)
			(stroke
				(width 0.1)
				(type default)
			)
			(layer "B.Fab")
		)
		(fp_line
			(start 0.12065 0.3048)
			(end 0.67945 0.3048)
			(stroke
				(width 0.1)
				(type default)
			)
			(layer "B.Fab")
		)
		(fp_line
			(start 0.67945 -0.305054)
			(end 0.12065 -0.305054)
			(stroke
				(width 0.1)
				(type default)
			)
			(layer "B.Fab")
		)
		(fp_line
			(start 0.67945 0.3048)
			(end 0.67945 -0.305054)
			(stroke
				(width 0.1)
				(type default)
			)
			(layer "B.Fab")
		)
		(pad "1" smd circle
			(at 0.40005 0 180)
			(size 0 0)
			(layers "B.Cu" "B.Mask" "B.Paste")
			(net "CLK_100M_DB800ZL_PEX3_S3_R_DN")
		)
		(pad "2" smd circle
			(at -0.40005 0 180)
			(size 0 0)
			(layers "B.Cu" "B.Mask" "B.Paste")
			(net "CLK_100M_DB800ZL_PEX3_S3_DN")
		)
	)
	(footprint ""
		(layer "B.Cu")
		(at 292.79977 -288.299906 90)
		(property "Reference" "C3269"
			(at 0 0 90)
			(layer "B.SilkS")
			(hide yes)
			(effects
				(font
					(size 1.27 1.27)
				)
				(justify mirror)
			)
		)
		(property "Value" ""
			(at 0 0 90)
			(layer "B.Fab")
			(effects
				(font
					(size 1.27 1.27)
				)
				(justify mirror)
			)
		)
		(duplicate_pad_numbers_are_jumpers no)
		(fp_line
			(start 0.299974 -0.150114)
			(end -0.299974 -0.150114)
			(stroke
				(width 0.1)
				(type default)
			)
			(layer "B.Fab")
		)
		(fp_line
			(start -0.299974 -0.150114)
			(end -0.299974 0.150114)
			(stroke
				(width 0.1)
				(type default)
			)
			(layer "B.Fab")
		)
		(fp_line
			(start 0.299974 0.150114)
			(end 0.299974 -0.150114)
			(stroke
				(width 0.1)
				(type default)
			)
			(layer "B.Fab")
		)
		(fp_line
			(start -0.299974 0.150114)
			(end 0.299974 0.150114)
			(stroke
				(width 0.1)
				(type default)
			)
			(layer "B.Fab")
		)
		(pad "1" smd rect
			(at 0.2667 0 270)
			(size 0.3048 0.381)
			(layers "B.Cu" "B.Mask" "B.Paste")
			(net "P1V25_PEX2")
		)
		(pad "2" smd rect
			(at -0.2667 0 270)
			(size 0.3048 0.381)
			(layers "B.Cu" "B.Mask" "B.Paste")
			(net "GND")
		)
	)
	(footprint ""
		(layer "B.Cu")
		(at 179.07508 -286.399732 90)
		(property "Reference" "C3138"
			(at 0 0 90)
			(layer "B.SilkS")
			(hide yes)
			(effects
				(font
					(size 1.27 1.27)
				)
				(justify mirror)
			)
		)
		(property "Value" ""
			(at 0 0 90)
			(layer "B.Fab")
			(effects
				(font
					(size 1.27 1.27)
				)
				(justify mirror)
			)
		)
		(duplicate_pad_numbers_are_jumpers no)
		(fp_line
			(start 0.299974 -0.150114)
			(end -0.299974 -0.150114)
			(stroke
				(width 0.1)
				(type default)
			)
			(layer "B.Fab")
		)
		(fp_line
			(start -0.299974 -0.150114)
			(end -0.299974 0.150114)
			(stroke
				(width 0.1)
				(type default)
			)
			(layer "B.Fab")
		)
		(fp_line
			(start 0.299974 0.150114)
			(end 0.299974 -0.150114)
			(stroke
				(width 0.1)
				(type default)
			)
			(layer "B.Fab")
		)
		(fp_line
			(start -0.299974 0.150114)
			(end 0.299974 0.150114)
			(stroke
				(width 0.1)
				(type default)
			)
			(layer "B.Fab")
		)
		(pad "1" smd rect
			(at 0.2667 0 270)
			(size 0.3048 0.381)
			(layers "B.Cu" "B.Mask" "B.Paste")
			(net "P1V25_SERDES_VDDPLL_PEX1")
		)
		(pad "2" smd rect
			(at -0.2667 0 270)
			(size 0.3048 0.381)
			(layers "B.Cu" "B.Mask" "B.Paste")
			(net "GND")
		)
	)
	(footprint ""
		(layer "B.Cu")
		(at 109.02315 -338.164424 180)
		(property "Reference" "C2701"
			(at 0 0 0)
			(layer "B.SilkS")
			(hide yes)
			(effects
				(font
					(size 1.27 1.27)
				)
				(justify mirror)
			)
		)
		(property "Value" ""
			(at 0 0 0)
			(layer "B.Fab")
			(effects
				(font
					(size 1.27 1.27)
				)
				(justify mirror)
			)
		)
		(duplicate_pad_numbers_are_jumpers no)
		(fp_line
			(start 1.524 0.762)
			(end 1.524 -0.762)
			(stroke
				(width 0.1524)
				(type default)
			)
			(layer "B.SilkS")
		)
		(fp_line
			(start 1.524 -0.762)
			(end -1.524 -0.762)
			(stroke
				(width 0.1524)
				(type default)
			)
			(layer "B.SilkS")
		)
		(fp_line
			(start -1.524 0.762)
			(end 1.524 0.762)
			(stroke
				(width 0.1524)
				(type default)
			)
			(layer "B.SilkS")
		)
		(fp_line
			(start -1.524 -0.762)
			(end -1.524 0.762)
			(stroke
				(width 0.1524)
				(type default)
			)
			(layer "B.SilkS")
		)
		(fp_line
			(start 1.1049 0.724916)
			(end -1.1049 0.724916)
			(stroke
				(width 0.1)
				(type default)
			)
			(layer "B.Fab")
		)
		(fp_line
			(start 1.1049 -0.724916)
			(end 1.1049 0.724916)
			(stroke
				(width 0.1)
				(type default)
			)
			(layer "B.Fab")
		)
		(fp_line
			(start -1.1049 0.724916)
			(end -1.1049 -0.724916)
			(stroke
				(width 0.1)
				(type default)
			)
			(layer "B.Fab")
		)
		(fp_line
			(start -1.1049 -0.724916)
			(end 1.1049 -0.724916)
			(stroke
				(width 0.1)
				(type default)
			)
			(layer "B.Fab")
		)
		(pad "1" smd rect
			(at 0.889 0 180)
			(size 1.016 1.27)
			(layers "B.Cu" "B.Mask" "B.Paste")
			(net "P3V3_CLK_BUFFER_9ZXL0451E_VZX3P3A")
		)
		(pad "2" smd rect
			(at -0.889 0 180)
			(size 1.016 1.27)
			(layers "B.Cu" "B.Mask" "B.Paste")
			(net "GND")
		)
	)
	(footprint ""
		(layer "B.Cu")
		(at 163.920424 -302.028606)
		(property "Reference" "C3163"
			(at 0 0 0)
			(layer "B.SilkS")
			(hide yes)
			(effects
				(font
					(size 1.27 1.27)
				)
				(justify mirror)
			)
		)
		(property "Value" ""
			(at 0 0 0)
			(layer "B.Fab")
			(effects
				(font
					(size 1.27 1.27)
				)
				(justify mirror)
			)
		)
		(duplicate_pad_numbers_are_jumpers no)
		(fp_line
			(start -1.2954 -0.5842)
			(end -1.2954 0.5842)
			(stroke
				(width 0.1524)
				(type default)
			)
			(layer "B.SilkS")
		)
		(fp_line
			(start -1.2954 0.5842)
			(end 1.2954 0.5842)
			(stroke
				(width 0.1524)
				(type default)
			)
			(layer "B.SilkS")
		)
		(fp_line
			(start 1.2954 -0.5842)
			(end -1.2954 -0.5842)
			(stroke
				(width 0.1524)
				(type default)
			)
			(layer "B.SilkS")
		)
		(fp_line
			(start 1.2954 0.5842)
			(end 1.2954 -0.5842)
			(stroke
				(width 0.1524)
				(type default)
			)
			(layer "B.SilkS")
		)
		(fp_line
			(start -1.1938 -0.4064)
			(end -1.1938 0.4064)
			(stroke
				(width 0.1)
				(type default)
			)
			(layer "B.Fab")
		)
		(fp_line
			(start -1.1938 0.4064)
			(end -0.8636 0.4064)
			(stroke
				(width 0.1)
				(type default)
			)
			(layer "B.Fab")
		)
		(fp_line
			(start -0.8636 -0.4572)
			(end -0.8636 -0.4064)
			(stroke
				(width 0.1)
				(type default)
			)
			(layer "B.Fab")
		)
		(fp_line
			(start -0.8636 -0.4064)
			(end -1.1938 -0.4064)
			(stroke
				(width 0.1)
				(type default)
			)
			(layer "B.Fab")
		)
		(fp_line
			(start -0.8636 0.4064)
			(end -0.8636 0.4572)
			(stroke
				(width 0.1)
				(type default)
			)
			(layer "B.Fab")
		)
		(fp_line
			(start -0.8636 0.4572)
			(end 0.8636 0.4572)
			(stroke
				(width 0.1)
				(type default)
			)
			(layer "B.Fab")
		)
		(fp_line
			(start 0.8636 -0.4572)
			(end -0.8636 -0.4572)
			(stroke
				(width 0.1)
				(type default)
			)
			(layer "B.Fab")
		)
		(fp_line
			(start 0.8636 -0.4064)
			(end 0.8636 -0.4572)
			(stroke
				(width 0.1)
				(type default)
			)
			(layer "B.Fab")
		)
		(fp_line
			(start 0.8636 0.4064)
			(end 1.1938 0.4064)
			(stroke
				(width 0.1)
				(type default)
			)
			(layer "B.Fab")
		)
		(fp_line
			(start 0.8636 0.4572)
			(end 0.8636 0.4064)
			(stroke
				(width 0.1)
				(type default)
			)
			(layer "B.Fab")
		)
		(fp_line
			(start 1.1938 -0.4064)
			(end 0.8636 -0.4064)
			(stroke
				(width 0.1)
				(type default)
			)
			(layer "B.Fab")
		)
		(fp_line
			(start 1.1938 0.4064)
			(end 1.1938 -0.4064)
			(stroke
				(width 0.1)
				(type default)
			)
			(layer "B.Fab")
		)
		(pad "1" smd rect
			(at 0.7366 0 270)
			(size 0.7112 0.8128)
			(layers "B.Cu" "B.Mask" "B.Paste")
			(net "P1V8_VDDA_PEX1")
		)
		(pad "2" smd rect
			(at -0.7366 0 270)
			(size 0.7112 0.8128)
			(layers "B.Cu" "B.Mask" "B.Paste")
			(net "GND")
		)
	)
	(footprint ""
		(layer "B.Cu")
		(at 61.101224 -305.399948 -90)
		(property "Reference" "C2978"
			(at 0 0 90)
			(layer "B.SilkS")
			(hide yes)
			(effects
				(font
					(size 1.27 1.27)
				)
				(justify mirror)
			)
		)
		(property "Value" ""
			(at 0 0 90)
			(layer "B.Fab")
			(effects
				(font
					(size 1.27 1.27)
				)
				(justify mirror)
			)
		)
		(duplicate_pad_numbers_are_jumpers no)
		(fp_line
			(start -0.299974 0.150114)
			(end 0.299974 0.150114)
			(stroke
				(width 0.1)
				(type default)
			)
			(layer "B.Fab")
		)
		(fp_line
			(start 0.299974 0.150114)
			(end 0.299974 -0.150114)
			(stroke
				(width 0.1)
				(type default)
			)
			(layer "B.Fab")
		)
		(fp_line
			(start -0.299974 -0.150114)
			(end -0.299974 0.150114)
			(stroke
				(width 0.1)
				(type default)
			)
			(layer "B.Fab")
		)
		(fp_line
			(start 0.299974 -0.150114)
			(end -0.299974 -0.150114)
			(stroke
				(width 0.1)
				(type default)
			)
			(layer "B.Fab")
		)
		(pad "1" smd rect
			(at 0.2667 0 90)
			(size 0.3048 0.381)
			(layers "B.Cu" "B.Mask" "B.Paste")
			(net "P1V25_SERDES_VDDPLL_PEX0")
		)
		(pad "2" smd rect
			(at -0.2667 0 90)
			(size 0.3048 0.381)
			(layers "B.Cu" "B.Mask" "B.Paste")
			(net "GND")
		)
	)
	(footprint ""
		(layer "B.Cu")
		(at 278.554942 -296.37482)
		(property "Reference" "C3376"
			(at 0 0 0)
			(layer "B.SilkS")
			(hide yes)
			(effects
				(font
					(size 1.27 1.27)
				)
				(justify mirror)
			)
		)
		(property "Value" ""
			(at 0 0 0)
			(layer "B.Fab")
			(effects
				(font
					(size 1.27 1.27)
				)
				(justify mirror)
			)
		)
		(duplicate_pad_numbers_are_jumpers no)
		(fp_line
			(start -0.299974 -0.150114)
			(end -0.299974 0.150114)
			(stroke
				(width 0.1)
				(type default)
			)
			(layer "B.Fab")
		)
		(fp_line
			(start -0.299974 0.150114)
			(end 0.299974 0.150114)
			(stroke
				(width 0.1)
				(type default)
			)
			(layer "B.Fab")
		)
		(fp_line
			(start 0.299974 -0.150114)
			(end -0.299974 -0.150114)
			(stroke
				(width 0.1)
				(type default)
			)
			(layer "B.Fab")
		)
		(fp_line
			(start 0.299974 0.150114)
			(end 0.299974 -0.150114)
			(stroke
				(width 0.1)
				(type default)
			)
			(layer "B.Fab")
		)
		(pad "1" smd rect
			(at 0.2667 0 180)
			(size 0.3048 0.381)
			(layers "B.Cu" "B.Mask" "B.Paste")
			(net "PCEPLL2_VDDA18_PEX2")
		)
		(pad "2" smd rect
			(at -0.2667 0 180)
			(size 0.3048 0.381)
			(layers "B.Cu" "B.Mask" "B.Paste")
			(net "GND")
		)
	)
)
